# BASEBOARD_FAB2 (Tioga Pass) — schematic netlist excerpt (pin names and nets, part order shuffled) for the footprints in the layout excerpt that follows; sources: Cadence DE-HDL packaged netlist, KiCad conversion of Wiwynn_Tioga_Pass_MB.brd

R3M11  RES  100.0 1% CHIP  pkg 0402  page 116 : A = A_PCIE_RCOMP_P ; B = A_PCIE_RCOMP_N
R25W166  RES  1.00K 1% CHIP  pkg 0402  page 255 : A = PD_GTL2014_DIR_6 ; B = GND
C2T24  CAP_A  0.1UF 16V 10% X7R  pkg 0402V  page 185 : A = P3V3 ; B = GND

(kicad_pcb
	(version 20260206)
	(generator "pcbnew")
	(generator_version "10.0")
	(general
		(thickness 1.6)
		(legacy_teardrops no)
	)
	(paper "A4")
	(title_block
		(title "Wiwynn_Tioga_Pass_MB.brd")
		(comment 1 "Tioga Pass / footprints 2500-2502 of 4770")
	)
	(layers
		(0 "F.Cu" signal "TOP")
		(4 "In1.Cu" signal "L2GND")
		(6 "In2.Cu" signal "L3")
		(8 "In3.Cu" signal "L4GND")
		(10 "In4.Cu" signal "L5")
		(12 "In5.Cu" signal "L6GND")
		(14 "In6.Cu" signal "L7VCC")
		(16 "In7.Cu" signal "L8VCC")
		(18 "In8.Cu" signal "L9GND")
		(20 "In9.Cu" signal "L10")
		(22 "In10.Cu" signal "L11GND")
		(24 "In11.Cu" signal "L12")
		(26 "In12.Cu" signal "L13GND")
		(2 "B.Cu" signal "BOTTOM")
		(9 "F.Adhes" user "F.Adhesive")
		(11 "B.Adhes" user "B.Adhesive")
		(13 "F.Paste" user "Package Geometry/Pastemask Top")
		(15 "B.Paste" user "Package Geometry/Pastemask Bottom")
		(5 "F.SilkS" user "Ref Des/Silkscreen Top")
		(7 "B.SilkS" user "Ref Des/Silkscreen Bottom")
		(1 "F.Mask" user "Board Geometry/Soldermask Top")
		(3 "B.Mask" user "Board Geometry/Soldermask Bottom")
		(17 "Dwgs.User" user "User.Drawings")
		(19 "Cmts.User" user "User.Comments")
		(21 "Eco1.User" user "User.Eco1")
		(23 "Eco2.User" user "User.Eco2")
		(25 "Edge.Cuts" user "Board Geometry/Outline")
		(27 "Margin" user)
		(31 "F.CrtYd" user "Package Geometry/Place Bound Top")
		(29 "B.CrtYd" user "Package Geometry/Place Bound Bottom")
		(35 "F.Fab" user "Ref Des/Assembly Top")
		(33 "B.Fab" user "Ref Des/Assembly Bottom")
	)
	(footprint ""
		(layer "B.Cu")
		(at 390.635744 -23.356316 -90)
		(property "Reference" "C2T24"
			(at 0 0 90)
			(layer "B.SilkS")
			(hide yes)
			(effects
				(font
					(size 1.27 1.27)
				)
				(justify mirror)
			)
		)
		(property "Value" ""
			(at 0 0 90)
			(layer "B.Fab")
			(effects
				(font
					(size 1.27 1.27)
				)
				(justify mirror)
			)
		)
		(duplicate_pad_numbers_are_jumpers no)
		(fp_poly
			(pts
				(xy -0.3048 -0.1016) (xy -0.3048 0.9906) (xy 0.3048 0.9906) (xy 0.3048 -0.1016)
			)
			(stroke
				(width 0)
				(type default)
			)
			(fill no)
			(layer "B.CrtYd")
		)
		(fp_line
			(start -0.3048 0.9906)
			(end -0.3048 -0.1016)
			(stroke
				(width 0.1)
				(type default)
			)
			(layer "B.Fab")
		)
		(fp_line
			(start 0.3048 0.9906)
			(end -0.3048 0.9906)
			(stroke
				(width 0.1)
				(type default)
			)
			(layer "B.Fab")
		)
		(fp_line
			(start -0.3048 -0.1016)
			(end 0.3048 -0.1016)
			(stroke
				(width 0.1)
				(type default)
			)
			(layer "B.Fab")
		)
		(fp_line
			(start 0.3048 -0.1016)
			(end 0.3048 0.9906)
			(stroke
				(width 0.1)
				(type default)
			)
			(layer "B.Fab")
		)
		(pad "1" smd rect
			(at 0 0 90)
			(size 0.508 0.508)
			(layers "B.Cu" "B.Mask" "B.Paste")
			(net "P3V3")
		)
		(pad "2" smd rect
			(at 0 0.889 90)
			(size 0.508 0.508)
			(layers "B.Cu" "B.Mask" "B.Paste")
			(net "GND")
		)
		(zone
			(layer "B.Cu")
			(hatch none 0.5)
			(connect_pads
				(clearance 0)
			)
			(min_thickness 0.25)
			(keepout
				(tracks not_allowed)
				(vias allowed)
				(pads allowed)
				(copperpour not_allowed)
				(footprints allowed)
			)
			(placement
				(enabled no)
				(sheetname "")
			)
			(fill
				(thermal_gap 0.5)
				(thermal_bridge_width 0.5)
				(island_removal_mode 0)
			)
			(polygon
				(pts
					(xy 390.000744 -23.102316) (xy 390.000744 -23.610316) (xy 390.381744 -23.610316) (xy 390.381744 -23.102316)
				)
			)
		)
		(zone
			(layer "B.Cu")
			(hatch none 0.5)
			(connect_pads
				(clearance 0)
			)
			(min_thickness 0.25)
			(keepout
				(tracks allowed)
				(vias not_allowed)
				(pads allowed)
				(copperpour not_allowed)
				(footprints allowed)
			)
			(placement
				(enabled no)
				(sheetname "")
			)
			(fill
				(thermal_gap 0.5)
				(thermal_bridge_width 0.5)
				(island_removal_mode 0)
			)
			(polygon
				(pts
					(xy 390.381744 -23.102316) (xy 390.381744 -23.610316) (xy 390.000744 -23.610316) (xy 390.000744 -23.102316)
				)
			)
		)
	)
	(footprint ""
		(layer "B.Cu")
		(at 450.215 -147.0406 -90)
		(property "Reference" "R25W166"
			(at 0.8382 -0.67818 270)
			(unlocked yes)
			(layer "B.SilkS")
			(effects
				(font
					(size 0.4064 0.254)
					(thickness 0.1524)
				)
				(justify left mirror)
			)
		)
		(property "Value" ""
			(at 0 0 90)
			(layer "B.Fab")
			(effects
				(font
					(size 1.27 1.27)
				)
				(justify mirror)
			)
		)
		(duplicate_pad_numbers_are_jumpers no)
		(fp_poly
			(pts
				(xy 0.2794 -0.1016) (xy -0.2794 -0.1016) (xy -0.2794 0.9906) (xy 0.2794 0.9906)
			)
			(stroke
				(width 0)
				(type default)
			)
			(fill no)
			(layer "B.CrtYd")
		)
		(fp_line
			(start -0.2794 0.9906)
			(end -0.2794 -0.1016)
			(stroke
				(width 0.1)
				(type default)
			)
			(layer "B.Fab")
		)
		(fp_line
			(start 0.2794 0.9906)
			(end -0.2794 0.9906)
			(stroke
				(width 0.1)
				(type default)
			)
			(layer "B.Fab")
		)
		(fp_line
			(start -0.2794 -0.1016)
			(end 0.2794 -0.1016)
			(stroke
				(width 0.1)
				(type default)
			)
			(layer "B.Fab")
		)
		(fp_line
			(start 0.2794 -0.1016)
			(end 0.2794 0.9906)
			(stroke
				(width 0.1)
				(type default)
			)
			(layer "B.Fab")
		)
		(pad "1" smd rect
			(at 0 0 90)
			(size 0.508 0.508)
			(layers "B.Cu" "B.Mask" "B.Paste")
			(net "PD_GTL2014_DIR_6")
		)
		(pad "2" smd rect
			(at 0 0.889 90)
			(size 0.508 0.508)
			(layers "B.Cu" "B.Mask" "B.Paste")
			(net "GND")
		)
		(zone
			(layer "B.Cu")
			(hatch none 0.5)
			(connect_pads
				(clearance 0)
			)
			(min_thickness 0.25)
			(keepout
				(tracks not_allowed)
				(vias allowed)
				(pads allowed)
				(copperpour not_allowed)
				(footprints allowed)
			)
			(placement
				(enabled no)
				(sheetname "")
			)
			(fill
				(thermal_gap 0.5)
				(thermal_bridge_width 0.5)
				(island_removal_mode 0)
			)
			(polygon
				(pts
					(xy 449.58 -146.7866) (xy 449.58 -147.2946) (xy 449.961 -147.2946) (xy 449.961 -146.7866)
				)
			)
		)
		(zone
			(layer "B.Cu")
			(hatch none 0.5)
			(connect_pads
				(clearance 0)
			)
			(min_thickness 0.25)
			(keepout
				(tracks allowed)
				(vias not_allowed)
				(pads allowed)
				(copperpour not_allowed)
				(footprints allowed)
			)
			(placement
				(enabled no)
				(sheetname "")
			)
			(fill
				(thermal_gap 0.5)
				(thermal_bridge_width 0.5)
				(island_removal_mode 0)
			)
			(polygon
				(pts
					(xy 449.961 -146.7866) (xy 449.961 -147.2946) (xy 449.58 -147.2946) (xy 449.58 -146.7866)
				)
			)
		)
	)
	(footprint ""
		(layer "B.Cu")
		(at 389.0518 -125.507242 90)
		(property "Reference" "R3M11"
			(at 0 0 90)
			(layer "B.SilkS")
			(hide yes)
			(effects
				(font
					(size 1.27 1.27)
				)
				(justify mirror)
			)
		)
		(property "Value" ""
			(at 0 0 90)
			(layer "B.Fab")
			(effects
				(font
					(size 1.27 1.27)
				)
				(justify mirror)
			)
		)
		(duplicate_pad_numbers_are_jumpers no)
		(fp_poly
			(pts
				(xy 0.2794 -0.1016) (xy -0.2794 -0.1016) (xy -0.2794 0.9906) (xy 0.2794 0.9906)
			)
			(stroke
				(width 0)
				(type default)
			)
			(fill no)
			(layer "B.CrtYd")
		)
		(fp_line
			(start 0.2794 -0.1016)
			(end 0.2794 0.9906)
			(stroke
				(width 0.1)
				(type default)
			)
			(layer "B.Fab")
		)
		(fp_line
			(start -0.2794 -0.1016)
			(end 0.2794 -0.1016)
			(stroke
				(width 0.1)
				(type default)
			)
			(layer "B.Fab")
		)
		(fp_line
			(start 0.2794 0.9906)
			(end -0.2794 0.9906)
			(stroke
				(width 0.1)
				(type default)
			)
			(layer "B.Fab")
		)
		(fp_line
			(start -0.2794 0.9906)
			(end -0.2794 -0.1016)
			(stroke
				(width 0.1)
				(type default)
			)
			(layer "B.Fab")
		)
		(pad "1" smd rect
			(at 0 0 270)
			(size 0.508 0.508)
			(layers "B.Cu" "B.Mask" "B.Paste")
			(net "A_PCIE_RCOMP_P")
		)
		(pad "2" smd rect
			(at 0 0.889 270)
			(size 0.508 0.508)
			(layers "B.Cu" "B.Mask" "B.Paste")
			(net "A_PCIE_RCOMP_N")
		)
		(zone
			(layer "B.Cu")
			(hatch none 0.5)
			(connect_pads
				(clearance 0)
			)
			(min_thickness 0.25)
			(keepout
				(tracks allowed)
				(vias not_allowed)
				(pads allowed)
				(copperpour not_allowed)
				(footprints allowed)
			)
			(placement
				(enabled no)
				(sheetname "")
			)
			(fill
				(thermal_gap 0.5)
				(thermal_bridge_width 0.5)
				(island_removal_mode 0)
			)
			(polygon
				(pts
					(xy 389.3058 -125.761242) (xy 389.3058 -125.253242) (xy 389.6868 -125.253242) (xy 389.6868 -125.761242)
				)
			)
		)
		(zone
			(layer "B.Cu")
			(hatch none 0.5)
			(connect_pads
				(clearance 0)
			)
			(min_thickness 0.25)
			(keepout
				(tracks not_allowed)
				(vias allowed)
				(pads allowed)
				(copperpour not_allowed)
				(footprints allowed)
			)
			(placement
				(enabled no)
				(sheetname "")
			)
			(fill
				(thermal_gap 0.5)
				(thermal_bridge_width 0.5)
				(island_removal_mode 0)
			)
			(polygon
				(pts
					(xy 389.6868 -125.761242) (xy 389.6868 -125.253242) (xy 389.3058 -125.253242) (xy 389.3058 -125.761242)
				)
			)
		)
	)
)
